# S9S_MB_2U (Grand Teton) — schematic netlist excerpt (pin names and nets, part order shuffled) for the footprints in the layout excerpt that follows; sources: Cadence DE-HDL packaged netlist, KiCad conversion of 03242023_DA0F0TMBIJ0_F0T_Motherboard_J_brd_V01_OCP.brd

J23  SCONN288_ADR50017P130CC  SCONN288_ADR50017-P130CC IO  pkg DDR288S_1-1VXB  page 104
  VIN_BULK0  = P12V_S3_AUX_CPU1_NVDIMM
  RFU0  = TP_CHD_CPU1_DIMM1_FRU_0
  VIN_MGMT  = P3V3_AUX
  HSCL  = I3C_SPD_DDRABCD_CPU1_LVC1_SCL_6
  HSDA  = I3C_SPD_DDRABCD_CPU1_LVC1_SDA
  VSS0  = GND
  DQ0_A  = M_D_CPU1_SA_DQ<0>
  VSS1  = GND
  DQ1_A  = M_D_CPU1_SA_DQ<1>
  VSS2  = GND
  DQS0_A_T  = M_D_CPU1_SA_DQS_DP<0>
  DQS0_A_C  = M_D_CPU1_SA_DQS_DN<0>
  VSS3  = GND
  DQ4_A  = M_D_CPU1_SA_DQ<4>
  VSS4  = GND
  DQ5_A  = M_D_CPU1_SA_DQ<5>
  VSS5  = GND
  DQ8_A  = M_D_CPU1_SA_DQ<8>
  VSS6  = GND
  DQ9_A  = M_D_CPU1_SA_DQ<9>
  VSS7  = GND
  DQS1_A_T  = M_D_CPU1_SA_DQS_DP<1>
  DQS1_A_C  = M_D_CPU1_SA_DQS_DN<1>
  VSS8  = GND
  DQ12_A  = M_D_CPU1_SA_DQ<12>
  VSS9  = GND
  DQ13_A  = M_D_CPU1_SA_DQ<13>
  VSS10  = GND
  DQ16_A  = M_D_CPU1_SA_DQ<16>
  VSS11  = GND
  DQ17_A  = M_D_CPU1_SA_DQ<17>
  VSS12  = GND
  DQS2_A_T  = M_D_CPU1_SA_DQS_DP<2>
  DQS2_A_C  = M_D_CPU1_SA_DQS_DN<2>
  VSS13  = GND
  DQ20_A  = M_D_CPU1_SA_DQ<20>
  VSS14  = GND
  DQ21_A  = M_D_CPU1_SA_DQ<21>
  VSS15  = GND
  DQ24_A  = M_D_CPU1_SA_DQ<24>
  VSS16  = GND
  DQ25_A  = M_D_CPU1_SA_DQ<25>
  VSS17  = GND
  DQS3_A_T  = M_D_CPU1_SA_DQS_DP<3>
  DQS3_A_C  = M_D_CPU1_SA_DQS_DN<3>
  VSS18  = GND
  DQ28_A  = M_D_CPU1_SA_DQ<28>
  VSS19  = GND
  DQ29_A  = M_D_CPU1_SA_DQ<29>
  VSS20  = GND
  CB0_A  = M_D_CPU1_SA_CB<0>
  VSS21  = GND
  CB1_A  = M_D_CPU1_SA_CB<1>
  VSS22  = GND
  DQS4_A_T  = M_D_CPU1_SA_DQS_DP<4>
  DQS4_A_C  = M_D_CPU1_SA_DQS_DN<4>
  VSS23  = GND
  CB4_A  = M_D_CPU1_SA_CB<4>
  VSS24  = GND
  CB5_A  = M_D_CPU1_SA_CB<5>
  VSS25  = GND
  ALERT_N  = M_D_CPU1_ALERT_N
  VSS26  = GND
  CS0_A_N  = M_D_CPU1_SA_CS_N<0>
  VSS27  = GND
  CA0_A  = M_D_CPU1_SA_CA<0>
  VSS28  = GND
  CA2_A  = M_D_CPU1_SA_CA<2>
  VSS29  = GND
  CA4_A  = M_D_CPU1_SA_CA<4>
  VSS30  = GND
  CA6_A  = M_D_CPU1_SA_CA<6>
  VSS31  = GND
  PAR_A  = M_D_CPU1_SA_PAR
  VSS32  = GND
  CA0_B  = M_D_CPU1_SB_CA<0>
  VSS33  = GND
  CA2_B  = M_D_CPU1_SB_CA<2>
  VSS34  = GND
  CA4_B  = M_D_CPU1_SB_CA<4>
  VSS35  = GND
  CA6_B  = M_D_CPU1_SB_CA<6>
  VSS36  = GND
  CS0_B_N  = M_D_CPU1_SB_CS_N<0>
  VSS37  = GND
  \lbd||rsp_a_n\  = M_D_CPU1_SA_RSP<0>
  \lbs||rsp_b_n\  = M_D_CPU1_SB_RSP<0>
  VSS38  = GND
  CB4_B  = M_D_CPU1_SB_CB<4>
  VSS39  = GND
  CB5_B  = M_D_CPU1_SB_CB<5>
  VSS40  = GND
  \dqs9_b_t||tdqs9_b_t||dbi4_b_n\  = M_D_CPU1_SB_DQS_DP<9>
  \dqs9_b_c||tdqs9_b_c\  = M_D_CPU1_SB_DQS_DN<9>
  VSS41  = GND
  CB0_B  = M_D_CPU1_SB_CB<0>
  VSS42  = GND
  CB1_B  = M_D_CPU1_SB_CB<1>
  VSS43  = GND
  DQ0_B  = M_D_CPU1_SB_DQ<0>
  VSS44  = GND
  DQ1_B  = M_D_CPU1_SB_DQ<1>
  VSS45  = GND
  DQS0_B_T  = M_D_CPU1_SB_DQS_DP<0>
  DQS0_B_C  = M_D_CPU1_SB_DQS_DN<0>
  VSS46  = GND
  DQ4_B  = M_D_CPU1_SB_DQ<4>
  VSS47  = GND
  DQ5_B  = M_D_CPU1_SB_DQ<5>
  VSS48  = GND
  DQ8_B  = M_D_CPU1_SB_DQ<8>
  VSS49  = GND
  DQ9_B  = M_D_CPU1_SB_DQ<9>
  VSS50  = GND
  DQS1_B_T  = M_D_CPU1_SB_DQS_DP<1>
  DQS1_B_C  = M_D_CPU1_SB_DQS_DN<1>
  VSS51  = GND
  DQ12_B  = M_D_CPU1_SB_DQ<12>
  VSS52  = GND
  DQ13_B  = M_D_CPU1_SB_DQ<13>
  VSS53  = GND
  DQ16_B  = M_D_CPU1_SB_DQ<16>
  VSS54  = GND
  DQ17_B  = M_D_CPU1_SB_DQ<17>
  VSS55  = GND
  DQS2_B_T  = M_D_CPU1_SB_DQS_DP<2>
  DQS2_B_C  = M_D_CPU1_SB_DQS_DN<2>
  VSS56  = GND
  DQ20_B  = M_D_CPU1_SB_DQ<20>
  VSS57  = GND
  DQ21_B  = M_D_CPU1_SB_DQ<21>
  VSS58  = GND
  DQ24_B  = M_D_CPU1_SB_DQ<24>
  VSS59  = GND
  DQ25_B  = M_D_CPU1_SB_DQ<25>
  VSS60  = GND
  DQS3_B_T  = M_D_CPU1_SB_DQS_DP<3>
  DQS3_B_C  = M_D_CPU1_SB_DQS_DN<3>
  VSS61  = GND
  DQ28_B  = M_D_CPU1_SB_DQ<28>
  VSS62  = GND
  DQ29_B  = M_D_CPU1_SB_DQ<29>
  VSS63  = GND
  RFU1  = TP_CHD_CPU1_DIMM1_FRU_1
  VIN_BULK1  = P12V_S3_AUX_CPU1_NVDIMM
  VIN_BULK2  = P12V_S3_AUX_CPU1_NVDIMM
  \pwr_good||fail_n\  = PWRGD_CHD_CPU1_DIMM1
  HSA  = PD_CHD_CPU1_DIMM1_SAA
  RFU2  = TP_CHD_CPU1_DIMM1_FRU_2
  RFU3  = TP_CHD_CPU1_DIMM1_FRU_3
  VSS64  = GND
  DQ2_A  = M_D_CPU1_SA_DQ<2>
  VSS65  = GND
  DQ3_A  = M_D_CPU1_SA_DQ<3>
  VSS66  = GND
  \dqs5_a_c||tdqs5_a_c||dqs5_a_t||tdqs5_a_t\  = M_D_CPU1_SA_DQS_DN<5>
  \dqs5_a_t||tdqs5_a_t\  = M_D_CPU1_SA_DQS_DP<5>
  VSS67  = GND
  DQ6_A  = M_D_CPU1_SA_DQ<6>
  VSS68  = GND
  DQ7_A  = M_D_CPU1_SA_DQ<7>
  VSS69  = GND
  DQ10_A  = M_D_CPU1_SA_DQ<10>
  VSS70  = GND
  DQ11_A  = M_D_CPU1_SA_DQ<11>
  VSS71  = GND
  \dqs6_a_c||tdqs6_a_c||dqs6_a_t||tdqs6_a_t\  = M_D_CPU1_SA_DQS_DN<6>
  \dqs6_a_t||tdqs6_a_t\  = M_D_CPU1_SA_DQS_DP<6>
  VSS72  = GND
  DQ14_A  = M_D_CPU1_SA_DQ<14>
  VSS73  = GND
  DQ15_A  = M_D_CPU1_SA_DQ<15>
  VSS74  = GND
  DQ18_A  = M_D_CPU1_SA_DQ<18>
  VSS75  = GND
  DQ19_A  = M_D_CPU1_SA_DQ<19>
  VSS76  = GND
  \dqs7_a_c||tdqs7_a_c\  = M_D_CPU1_SA_DQS_DN<7>
  \dqs7_a_t||tdqs7_a_t\  = M_D_CPU1_SA_DQS_DP<7>
  VSS77  = GND
  DQ22_A  = M_D_CPU1_SA_DQ<22>
  VSS78  = GND
  DQ23_A  = M_D_CPU1_SA_DQ<23>
  VSS79  = GND
  DQ26_A  = M_D_CPU1_SA_DQ<26>
  VSS80  = GND
  DQ27_A  = M_D_CPU1_SA_DQ<27>
  VSS81  = GND
  \dqs8_a_c||tdqs8_a_c\  = M_D_CPU1_SA_DQS_DN<8>
  \dqs8_a_t||tdqs8_a_t\  = M_D_CPU1_SA_DQS_DP<8>
  VSS82  = GND
  DQ30_A  = M_D_CPU1_SA_DQ<30>
  VSS83  = GND
  DQ31_A  = M_D_CPU1_SA_DQ<31>
  VSS84  = GND
  CB2_A  = M_D_CPU1_SA_CB<2>
  VSS85  = GND
  CB3_A  = M_D_CPU1_SA_CB<3>
  VSS86  = GND
  \dqs9_a_c||tdqs9_a_c\  = M_D_CPU1_SA_DQS_DN<9>
  \dqs9_a_t||tdqs9_a_t\  = M_D_CPU1_SA_DQS_DP<9>
  VSS87  = GND
  CB6_A  = M_D_CPU1_SA_CB<6>
  VSS88  = GND
  CB7_A  = M_D_CPU1_SA_CB<7>
  VSS89  = GND
  RESET_N  = RST_M_CD_CPU1_FPGA_N
  VSS90  = GND
  CS1_A_N  = M_D_CPU1_SA_CS_N<1>
  VSS91  = GND
  CA1_A  = M_D_CPU1_SA_CA<1>
  VSS92  = GND
  CA3_A  = M_D_CPU1_SA_CA<3>
  VSS93  = GND
  CA5_A  = M_D_CPU1_SA_CA<5>
  VSS94  = GND
  CK_T  = M_D_CPU1_CLK_DP<0>
  CK_C  = M_D_CPU1_CLK_DN<0>
  VSS95  = GND
  RFU4  = TP_CHD_CPU1_DIMM1_FRU_4
  CA1_B  = M_D_CPU1_SB_CA<1>
  VSS96  = GND
  CA3_B  = M_D_CPU1_SB_CA<3>
  VSS97  = GND
  CA5_B  = M_D_CPU1_SB_CA<5>
  VSS98  = GND
  PAR_B  = M_D_CPU1_SB_PAR
  VSS99  = GND
  CS1_B_N  = M_D_CPU1_SB_CS_N<1>
  VSS100  = GND
  RFU5  = TP_CHD_CPU1_DIMM1_FRU_5
  RFU6  = TP_CHD_CPU1_DIMM1_FRU_6
  VSS101  = GND
  CB6_B  = M_D_CPU1_SB_CB<6>
  VSS102  = GND
  CB7_B  = M_D_CPU1_SB_CB<7>
  VSS103  = GND
  DQS4_B_C  = M_D_CPU1_SB_DQS_DN<4>
  DQS4_B_T  = M_D_CPU1_SB_DQS_DP<4>
  VSS104  = GND
  CB2_B  = M_D_CPU1_SB_CB<2>
  VSS105  = GND
  CB3_B  = M_D_CPU1_SB_CB<3>
  VSS106  = GND
  DQ2_B  = M_D_CPU1_SB_DQ<2>
  VSS107  = GND
  DQ3_B  = M_D_CPU1_SB_DQ<3>
  VSS108  = GND
  \dqs5_b_c||tdqs5_b_c\  = M_D_CPU1_SB_DQS_DN<5>
  \dqs5_b_t||tdqs5_b_t\  = M_D_CPU1_SB_DQS_DP<5>
  VSS109  = GND
  DQ6_B  = M_D_CPU1_SB_DQ<6>
  VSS110  = GND
  DQ7_B  = M_D_CPU1_SB_DQ<7>
  VSS111  = GND
  DQ10_B  = M_D_CPU1_SB_DQ<10>
  VSS112  = GND
  DQ11_B  = M_D_CPU1_SB_DQ<11>
  VSS113  = GND
  \dqs6_b_c||tdqs6_b_c\  = M_D_CPU1_SB_DQS_DN<6>
  \dqs6_b_t||tdqs6_b_t\  = M_D_CPU1_SB_DQS_DP<6>
  VSS114  = GND
  DQ14_B  = M_D_CPU1_SB_DQ<14>
  VSS115  = GND
  DQ15_B  = M_D_CPU1_SB_DQ<15>
  VSS116  = GND
  DQ18_B  = M_D_CPU1_SB_DQ<18>
  VSS117  = GND
  DQ19_B  = M_D_CPU1_SB_DQ<19>
  VSS118  = GND
  \dqs7_b_c||tdqs7_b_c\  = M_D_CPU1_SB_DQS_DN<7>
  \dqs7_b_t||tdqs7_b_t\  = M_D_CPU1_SB_DQS_DP<7>
  VSS119  = GND
  DQ22_B  = M_D_CPU1_SB_DQ<22>
  VSS120  = GND
  DQ23_B  = M_D_CPU1_SB_DQ<23>
  VSS121  = GND
  DQ26_B  = M_D_CPU1_SB_DQ<26>
  VSS122  = GND
  DQ27_B  = M_D_CPU1_SB_DQ<27>
  VSS123  = GND
  \dqs8_b_c||tdqs8_b_c\  = M_D_CPU1_SB_DQS_DN<8>
  \dqs8_b_t||tdqs8_b_t\  = M_D_CPU1_SB_DQS_DP<8>
  VSS124  = GND
  DQ30_B  = M_D_CPU1_SB_DQ<30>
  VSS125  = GND
  DQ31_B  = M_D_CPU1_SB_DQ<31>
  VSS126  = GND
  G1  = GND
  G2  = GND
  G3  = GND

(kicad_pcb
	(version 20260206)
	(generator "pcbnew")
	(generator_version "10.0")
	(general
		(thickness 1.6)
		(legacy_teardrops no)
	)
	(paper "A4")
	(title_block
		(title "03242023_DA0F0TMBIJ0_F0T_Motherboard_J_brd_V01_OCP.brd")
		(comment 1 "Grand Teton / footprint 3586 of 6105 (J23), pads 183-228 of 291")
	)
	(layers
		(0 "F.Cu" signal "TOP")
		(4 "In1.Cu" signal "GND")
		(6 "In2.Cu" signal "IN1")
		(8 "In3.Cu" signal "GND1")
		(10 "In4.Cu" signal "IN2")
		(12 "In5.Cu" signal "GND2")
		(14 "In6.Cu" signal "IN3")
		(16 "In7.Cu" signal "GND3")
		(18 "In8.Cu" signal "VCC")
		(20 "In9.Cu" signal "VCC1")
		(22 "In10.Cu" signal "GND4")
		(24 "In11.Cu" signal "IN4")
		(26 "In12.Cu" signal "GND5")
		(28 "In13.Cu" signal "IN5")
		(30 "In14.Cu" signal "GND6")
		(32 "In15.Cu" signal "IN6")
		(34 "In16.Cu" signal "GND7")
		(2 "B.Cu" signal "BOTTOM")
		(9 "F.Adhes" user "F.Adhesive")
		(11 "B.Adhes" user "B.Adhesive")
		(13 "F.Paste" user "Package Geometry/Pastemask Top")
		(15 "B.Paste" user "Package Geometry/Pastemask Bottom")
		(5 "F.SilkS" user "Ref Des/Silkscreen Top")
		(7 "B.SilkS" user "Ref Des/Silkscreen Bottom")
		(1 "F.Mask" user "Board Geometry/Soldermask Top")
		(3 "B.Mask" user "Board Geometry/Soldermask Bottom")
		(17 "Dwgs.User" user "User.Drawings")
		(19 "Cmts.User" user "User.Comments")
		(21 "Eco1.User" user "User.Eco1")
		(23 "Eco2.User" user "User.Eco2")
		(25 "Edge.Cuts" user "Board Geometry/Outline")
		(27 "Margin" user)
		(31 "F.CrtYd" user "Package Geometry/Place Bound Top")
		(29 "B.CrtYd" user "Package Geometry/Place Bound Bottom")
		(35 "F.Fab" user "Ref Des/Assembly Top")
		(33 "B.Fab" user "Ref Des/Assembly Bottom")
	)
	(footprint ""
		(layer "F.Cu")
		(at 10.19048 -258.091686)
		(property "Reference" "J23"
			(at -5.69468 -80.480408 0)
			(unlocked yes)
			(layer "F.SilkS")
			(effects
				(font
					(size 0.7874 0.5842)
					(thickness 0.1524)
				)
				(justify left)
			)
		)
		(property "Value" ""
			(at 0 0 0)
			(layer "F.Fab")
			(effects
				(font
					(size 1.27 1.27)
				)
			)
		)
		(duplicate_pad_numbers_are_jumpers no)
		(pad "183" smd rect
			(at 2.050034 -31.025084 270)
			(size 0.519938 1.4986)
			(layers "F.Cu" "F.Mask" "F.Paste")
			(net "M_D_CPU1_SA_DQ<23>")
		)
		(pad "184" smd rect
			(at 2.050034 -30.174946 270)
			(size 0.519938 1.4986)
			(layers "F.Cu" "F.Mask" "F.Paste")
			(net "GND")
		)
		(pad "185" smd rect
			(at 2.050034 -29.325062 270)
			(size 0.519938 1.4986)
			(layers "F.Cu" "F.Mask" "F.Paste")
			(net "M_D_CPU1_SA_DQ<26>")
		)
		(pad "186" smd rect
			(at 2.050034 -28.474924 270)
			(size 0.519938 1.4986)
			(layers "F.Cu" "F.Mask" "F.Paste")
			(net "GND")
		)
		(pad "187" smd rect
			(at 2.050034 -27.62504 270)
			(size 0.519938 1.4986)
			(layers "F.Cu" "F.Mask" "F.Paste")
			(net "M_D_CPU1_SA_DQ<27>")
		)
		(pad "188" smd rect
			(at 2.050034 -26.774902 270)
			(size 0.519938 1.4986)
			(layers "F.Cu" "F.Mask" "F.Paste")
			(net "GND")
		)
		(pad "189" smd rect
			(at 2.050034 -25.925018 270)
			(size 0.519938 1.4986)
			(layers "F.Cu" "F.Mask" "F.Paste")
			(net "M_D_CPU1_SA_DQS_DN<8>")
		)
		(pad "190" smd rect
			(at 2.050034 -25.07488 270)
			(size 0.519938 1.4986)
			(layers "F.Cu" "F.Mask" "F.Paste")
			(net "M_D_CPU1_SA_DQS_DP<8>")
		)
		(pad "191" smd rect
			(at 2.050034 -24.224996 270)
			(size 0.519938 1.4986)
			(layers "F.Cu" "F.Mask" "F.Paste")
			(net "GND")
		)
		(pad "192" smd rect
			(at 2.050034 -23.375112 270)
			(size 0.519938 1.4986)
			(layers "F.Cu" "F.Mask" "F.Paste")
			(net "M_D_CPU1_SA_DQ<30>")
		)
		(pad "193" smd rect
			(at 2.050034 -22.524974 270)
			(size 0.519938 1.4986)
			(layers "F.Cu" "F.Mask" "F.Paste")
			(net "GND")
		)
		(pad "194" smd rect
			(at 2.050034 -21.67509 270)
			(size 0.519938 1.4986)
			(layers "F.Cu" "F.Mask" "F.Paste")
			(net "M_D_CPU1_SA_DQ<31>")
		)
		(pad "195" smd rect
			(at 2.050034 -20.824952 270)
			(size 0.519938 1.4986)
			(layers "F.Cu" "F.Mask" "F.Paste")
			(net "GND")
		)
		(pad "196" smd rect
			(at 2.050034 -19.975068 270)
			(size 0.519938 1.4986)
			(layers "F.Cu" "F.Mask" "F.Paste")
			(net "M_D_CPU1_SA_CB<2>")
		)
		(pad "197" smd rect
			(at 2.050034 -19.12493 270)
			(size 0.519938 1.4986)
			(layers "F.Cu" "F.Mask" "F.Paste")
			(net "GND")
		)
		(pad "198" smd rect
			(at 2.050034 -18.275046 270)
			(size 0.519938 1.4986)
			(layers "F.Cu" "F.Mask" "F.Paste")
			(net "M_D_CPU1_SA_CB<3>")
		)
		(pad "199" smd rect
			(at 2.050034 -17.424908 270)
			(size 0.519938 1.4986)
			(layers "F.Cu" "F.Mask" "F.Paste")
			(net "GND")
		)
		(pad "200" smd rect
			(at 2.050034 -16.575024 270)
			(size 0.519938 1.4986)
			(layers "F.Cu" "F.Mask" "F.Paste")
			(net "M_D_CPU1_SA_DQS_DN<9>")
		)
		(pad "201" smd rect
			(at 2.050034 -15.724886 270)
			(size 0.519938 1.4986)
			(layers "F.Cu" "F.Mask" "F.Paste")
			(net "M_D_CPU1_SA_DQS_DP<9>")
		)
		(pad "202" smd rect
			(at 2.050034 -14.875002 270)
			(size 0.519938 1.4986)
			(layers "F.Cu" "F.Mask" "F.Paste")
			(net "GND")
		)
		(pad "203" smd rect
			(at 2.050034 -14.025118 270)
			(size 0.519938 1.4986)
			(layers "F.Cu" "F.Mask" "F.Paste")
			(net "M_D_CPU1_SA_CB<6>")
		)
		(pad "204" smd rect
			(at 2.050034 -13.17498 270)
			(size 0.519938 1.4986)
			(layers "F.Cu" "F.Mask" "F.Paste")
			(net "GND")
		)
		(pad "205" smd rect
			(at 2.050034 -12.325096 270)
			(size 0.519938 1.4986)
			(layers "F.Cu" "F.Mask" "F.Paste")
			(net "M_D_CPU1_SA_CB<7>")
		)
		(pad "206" smd rect
			(at 2.050034 -11.474958 270)
			(size 0.519938 1.4986)
			(layers "F.Cu" "F.Mask" "F.Paste")
			(net "GND")
		)
		(pad "207" smd rect
			(at 2.050034 -10.625074 270)
			(size 0.519938 1.4986)
			(layers "F.Cu" "F.Mask" "F.Paste")
			(net "RST_M_CD_CPU1_FPGA_N")
		)
		(pad "208" smd rect
			(at 2.050034 -9.774936 270)
			(size 0.519938 1.4986)
			(layers "F.Cu" "F.Mask" "F.Paste")
			(net "GND")
		)
		(pad "209" smd rect
			(at 2.050034 -8.925052 270)
			(size 0.519938 1.4986)
			(layers "F.Cu" "F.Mask" "F.Paste")
			(net "M_D_CPU1_SA_CS_N<1>")
		)
		(pad "210" smd rect
			(at 2.050034 -8.074914 270)
			(size 0.519938 1.4986)
			(layers "F.Cu" "F.Mask" "F.Paste")
			(net "GND")
		)
		(pad "211" smd rect
			(at 2.050034 -7.22503 270)
			(size 0.519938 1.4986)
			(layers "F.Cu" "F.Mask" "F.Paste")
			(net "M_D_CPU1_SA_CA<1>")
		)
		(pad "212" smd rect
			(at 2.050034 -6.374892 270)
			(size 0.519938 1.4986)
			(layers "F.Cu" "F.Mask" "F.Paste")
			(net "GND")
		)
		(pad "213" smd rect
			(at 2.050034 -5.525008 270)
			(size 0.519938 1.4986)
			(layers "F.Cu" "F.Mask" "F.Paste")
			(net "M_D_CPU1_SA_CA<3>")
		)
		(pad "214" smd rect
			(at 2.050034 -4.675124 270)
			(size 0.519938 1.4986)
			(layers "F.Cu" "F.Mask" "F.Paste")
			(net "GND")
		)
		(pad "215" smd rect
			(at 2.050034 -3.824986 270)
			(size 0.519938 1.4986)
			(layers "F.Cu" "F.Mask" "F.Paste")
			(net "M_D_CPU1_SA_CA<5>")
		)
		(pad "216" smd rect
			(at 2.050034 -2.975102 270)
			(size 0.519938 1.4986)
			(layers "F.Cu" "F.Mask" "F.Paste")
			(net "GND")
		)
		(pad "217" smd rect
			(at 2.050034 -2.124964 270)
			(size 0.519938 1.4986)
			(layers "F.Cu" "F.Mask" "F.Paste")
			(net "M_D_CPU1_CLK_DP<0>")
		)
		(pad "218" smd rect
			(at 2.050034 -1.27508 270)
			(size 0.519938 1.4986)
			(layers "F.Cu" "F.Mask" "F.Paste")
			(net "M_D_CPU1_CLK_DN<0>")
		)
		(pad "219" smd rect
			(at 2.050034 -0.424942 270)
			(size 0.519938 1.4986)
			(layers "F.Cu" "F.Mask" "F.Paste")
			(net "GND")
		)
		(pad "220" smd rect
			(at 2.050034 5.525008 270)
			(size 0.519938 1.4986)
			(layers "F.Cu" "F.Mask" "F.Paste")
			(net "TP_CHD_CPU1_DIMM1_FRU_4")
		)
		(pad "221" smd rect
			(at 2.050034 6.374892 270)
			(size 0.519938 1.4986)
			(layers "F.Cu" "F.Mask" "F.Paste")
			(net "M_D_CPU1_SB_CA<1>")
		)
		(pad "222" smd rect
			(at 2.050034 7.22503 270)
			(size 0.519938 1.4986)
			(layers "F.Cu" "F.Mask" "F.Paste")
			(net "GND")
		)
		(pad "223" smd rect
			(at 2.050034 8.074914 270)
			(size 0.519938 1.4986)
			(layers "F.Cu" "F.Mask" "F.Paste")
			(net "M_D_CPU1_SB_CA<3>")
		)
		(pad "224" smd rect
			(at 2.050034 8.925052 270)
			(size 0.519938 1.4986)
			(layers "F.Cu" "F.Mask" "F.Paste")
			(net "GND")
		)
		(pad "225" smd rect
			(at 2.050034 9.774936 270)
			(size 0.519938 1.4986)
			(layers "F.Cu" "F.Mask" "F.Paste")
			(net "M_D_CPU1_SB_CA<5>")
		)
		(pad "226" smd rect
			(at 2.050034 10.625074 270)
			(size 0.519938 1.4986)
			(layers "F.Cu" "F.Mask" "F.Paste")
			(net "GND")
		)
		(pad "227" smd rect
			(at 2.050034 11.474958 270)
			(size 0.519938 1.4986)
			(layers "F.Cu" "F.Mask" "F.Paste")
			(net "M_D_CPU1_SB_PAR")
		)
		(pad "228" smd rect
			(at 2.050034 12.325096 270)
			(size 0.519938 1.4986)
			(layers "F.Cu" "F.Mask" "F.Paste")
			(net "GND")
		)
	)
)
